(kicad_pcb
	(version 20260206)
	(generator "pcbnew")
	(generator_version "10.0")
	(general
		(thickness 0.77098)
		(legacy_teardrops no)
	)
	(paper "A4")
	(title_block
		(title "gnss-m2-zed-f9t — M2_ZED-F9T_MODULE.PcbDoc")
		(comment 1 "Time Appliance Project (Time Card) / footprints 15-22 of 36")
	)
	(layers
		(0 "F.Cu" signal "L01-Top Layer")
		(4 "In1.Cu" signal "L02-Inner Layer")
		(6 "In2.Cu" signal "L03-Inner Layer")
		(2 "B.Cu" signal "L04-Bottom Layer")
		(9 "F.Adhes" user "F.Adhesive")
		(11 "B.Adhes" user "B.Adhesive")
		(13 "F.Paste" user "Top Paste")
		(15 "B.Paste" user "Bottom Paste")
		(5 "F.SilkS" user "Top Overlay")
		(7 "B.SilkS" user "Bottom Overlay")
		(1 "F.Mask" user "Top Solder")
		(3 "B.Mask" user "Bottom Solder")
		(17 "Dwgs.User" user "User.Drawings")
		(19 "Cmts.User" user "User.Comments")
		(21 "Eco1.User" user "User.Eco1")
		(23 "Eco2.User" user "User.Eco2")
		(25 "Edge.Cuts" user)
		(27 "Margin" user)
		(31 "F.CrtYd" user "Top Courtyard")
		(29 "B.CrtYd" user "Bottom Courtyard")
		(35 "F.Fab" user "Top Component Outline")
		(33 "B.Fab" user "Bottom Component Outline 2")
	)
	(footprint "Vault:FP-CL542-IPC_C"
		(layer "F.Cu")
		(at 150.701105 111.5036)
		(property "Reference" "C4"
			(at 1.284665 0.419515 0)
			(unlocked yes)
			(layer "F.SilkS")
			(effects
				(font
					(face "Arial")
					(size 0.40005 0.40005)
					(thickness 0.1778)
				)
			)
		)
		(property "Value" "1uF_25V_0402"
			(at 5.01461 2.213735 0)
			(unlocked yes)
			(layer "F.SilkS")
			(hide yes)
			(effects
				(font
					(face "Arial")
					(size 0.40005 0.40005)
					(thickness 0.1778)
				)
			)
		)
		(sheetname "01-M2_ZED-F9T_MODULE")
		(sheetfile "01-M2_ZED-F9T_MODULE.kicad_sch")
		(duplicate_pad_numbers_are_jumpers no)
		(fp_line
			(start -0.73624 -0.375)
			(end 0.73624 -0.375)
			(stroke
				(width 0.2)
				(type solid)
			)
			(layer "F.CrtYd")
		)
		(fp_line
			(start -0.73624 0.375)
			(end -0.73624 -0.375)
			(stroke
				(width 0.2)
				(type solid)
			)
			(layer "F.CrtYd")
		)
		(fp_line
			(start -0.73624 0.375)
			(end 0.73624 0.375)
			(stroke
				(width 0.2)
				(type solid)
			)
			(layer "F.CrtYd")
		)
		(fp_line
			(start 0.73624 0.375)
			(end 0.73624 -0.375)
			(stroke
				(width 0.2)
				(type solid)
			)
			(layer "F.CrtYd")
		)
		(fp_line
			(start -0.73624 -0.375)
			(end 0.73624 -0.375)
			(stroke
				(width 0.2)
				(type solid)
			)
			(layer "F.Fab")
		)
		(fp_line
			(start -0.73624 0.375)
			(end -0.73624 -0.375)
			(stroke
				(width 0.2)
				(type solid)
			)
			(layer "F.Fab")
		)
		(fp_line
			(start -0.73624 0.375)
			(end 0.73624 0.375)
			(stroke
				(width 0.2)
				(type solid)
			)
			(layer "F.Fab")
		)
		(fp_line
			(start -0.5 0)
			(end 0.5 0)
			(stroke
				(width 0.1)
				(type solid)
			)
			(layer "F.Fab")
		)
		(fp_line
			(start -0.5 0)
			(end 0.5 0)
			(stroke
				(width 0.1)
				(type solid)
			)
			(layer "F.Fab")
		)
		(fp_line
			(start 0 0.5)
			(end 0 -0.5)
			(stroke
				(width 0.1)
				(type solid)
			)
			(layer "F.Fab")
		)
		(fp_line
			(start 0 0.5)
			(end 0 -0.5)
			(stroke
				(width 0.1)
				(type solid)
			)
			(layer "F.Fab")
		)
		(fp_line
			(start 0.73624 0.375)
			(end 0.73624 -0.375)
			(stroke
				(width 0.2)
				(type solid)
			)
			(layer "F.Fab")
		)
		(fp_text user "${REFERENCE}"
			(at 0 0.28425 360)
			(unlocked yes)
			(layer "F.Fab")
			(effects
				(font
					(face "Arial")
					(size 0.63 0.63)
					(thickness 0.1)
				)
				(justify left bottom)
			)
		)
		(pad "1" smd rect
			(at -0.37856 0)
			(size 0.51535 0.47247)
			(layers "F.Cu" "F.Mask" "F.Paste")
			(net "+3V3")
			(solder_mask_margin 0)
			(solder_paste_margin 0)
		)
		(pad "2" smd rect
			(at 0.37856 0)
			(size 0.51535 0.47247)
			(layers "F.Cu" "F.Mask" "F.Paste")
			(net "GND")
			(solder_mask_margin 0)
			(solder_paste_margin 0)
		)
	)
	(footprint "Vault:FP-0402-L_1_0_0_05-W_0_5-IPC_B"
		(layer "F.Cu")
		(at 154.601105 91.1036 90)
		(property "Reference" "C10"
			(at -0.20001 2.992629 270)
			(unlocked yes)
			(layer "F.SilkS")
			(effects
				(font
					(face "Arial")
					(size 0.96012 0.96012)
					(thickness 0.254)
				)
			)
		)
		(property "Value" "100nF"
			(at -2.303171 2.90719 0)
			(unlocked yes)
			(layer "F.SilkS")
			(hide yes)
			(effects
				(font
					(face "Arial")
					(size 0.96012 0.96012)
					(thickness 0.254)
				)
			)
		)
		(sheetname "02-Antenna_Supervisor")
		(sheetfile "02-Antenna_Supervisor.kicad_sch")
		(duplicate_pad_numbers_are_jumpers no)
		(fp_line
			(start 0.88624 -0.43624)
			(end 0.88624 0.43624)
			(stroke
				(width 0.2)
				(type solid)
			)
			(layer "F.CrtYd")
		)
		(fp_line
			(start -0.88624 -0.43624)
			(end 0.88624 -0.43624)
			(stroke
				(width 0.2)
				(type solid)
			)
			(layer "F.CrtYd")
		)
		(fp_line
			(start -0.88624 -0.43624)
			(end -0.88624 0.43624)
			(stroke
				(width 0.2)
				(type solid)
			)
			(layer "F.CrtYd")
		)
		(fp_line
			(start -0.88624 0.43624)
			(end 0.88624 0.43624)
			(stroke
				(width 0.2)
				(type solid)
			)
			(layer "F.CrtYd")
		)
		(fp_line
			(start 0 -0.5)
			(end 0 0.5)
			(stroke
				(width 0.1)
				(type solid)
			)
			(layer "F.Fab")
		)
		(fp_line
			(start 0.88624 -0.43624)
			(end 0.88624 0.43624)
			(stroke
				(width 0.2)
				(type solid)
			)
			(layer "F.Fab")
		)
		(fp_line
			(start -0.88624 -0.43624)
			(end 0.88624 -0.43624)
			(stroke
				(width 0.2)
				(type solid)
			)
			(layer "F.Fab")
		)
		(fp_line
			(start -0.88624 -0.43624)
			(end -0.88624 0.43624)
			(stroke
				(width 0.2)
				(type solid)
			)
			(layer "F.Fab")
		)
		(fp_line
			(start -0.5 0)
			(end 0.5 0)
			(stroke
				(width 0.1)
				(type solid)
			)
			(layer "F.Fab")
		)
		(fp_line
			(start -0.88624 0.43624)
			(end 0.88624 0.43624)
			(stroke
				(width 0.2)
				(type solid)
			)
			(layer "F.Fab")
		)
		(fp_text user "${REFERENCE}"
			(at -0.00001 0.09602 90)
			(unlocked yes)
			(layer "F.Fab")
			(effects
				(font
					(face "Arial")
					(size 0.63 0.63)
					(thickness 0.1)
				)
				(justify left bottom)
			)
		)
		(pad "1" smd rect
			(at -0.42856 0 90)
			(size 0.61535 0.57247)
			(layers "F.Cu" "F.Mask" "F.Paste")
			(net "RF_IN")
			(solder_mask_margin 0)
			(solder_paste_margin 0)
		)
		(pad "2" smd rect
			(at 0.42856 0 90)
			(size 0.61535 0.57247)
			(layers "F.Cu" "F.Mask" "F.Paste")
			(net "RF_ANT")
			(solder_mask_margin 0)
			(solder_paste_margin 0)
		)
	)
	(footprint "Vault:RESC1005X40X25NL05T10"
		(layer "F.Cu")
		(at 145.601105 117.9036 -90)
		(property "Reference" "R13"
			(at 0.6 -0.800076 90)
			(unlocked yes)
			(layer "F.SilkS")
			(effects
				(font
					(face "Arial")
					(size 0.48006 0.48006)
					(thickness 0.254)
				)
			)
		)
		(property "Value" "0_5%_0402"
			(at -2.385831 6.512925 180)
			(unlocked yes)
			(layer "F.SilkS")
			(hide yes)
			(effects
				(font
					(face "Arial")
					(size 0.96012 0.96012)
					(thickness 0.254)
				)
			)
		)
		(sheetname "03-M2_GoldFingers")
		(sheetfile "03-M2_GoldFingers.kicad_sch")
		(duplicate_pad_numbers_are_jumpers no)
		(fp_line
			(start -0.9 0.45)
			(end -0.9 -0.45)
			(stroke
				(width 0.05)
				(type solid)
			)
			(layer "F.CrtYd")
		)
		(fp_line
			(start 0.9 0.45)
			(end -0.9 0.45)
			(stroke
				(width 0.05)
				(type solid)
			)
			(layer "F.CrtYd")
		)
		(fp_line
			(start 0.9 0.45)
			(end 0.9 -0.45)
			(stroke
				(width 0.05)
				(type solid)
			)
			(layer "F.CrtYd")
		)
		(fp_line
			(start 0 0.275)
			(end 0 -0.275)
			(stroke
				(width 0.1)
				(type solid)
			)
			(layer "F.CrtYd")
		)
		(fp_line
			(start 0.275 0)
			(end -0.275 0)
			(stroke
				(width 0.1)
				(type solid)
			)
			(layer "F.CrtYd")
		)
		(fp_line
			(start 0.9 -0.45)
			(end -0.9 -0.45)
			(stroke
				(width 0.05)
				(type solid)
			)
			(layer "F.CrtYd")
		)
		(pad "1" smd rect
			(at -0.425 0)
			(size 0.55 0.6)
			(layers "F.Cu" "F.Mask" "F.Paste")
			(net "RST_GPS")
		)
		(pad "2" smd rect
			(at 0.425 0)
			(size 0.55 0.6)
			(layers "F.Cu" "F.Mask" "F.Paste")
			(net "NetJ1_50")
		)
	)
	(footprint "Vault:FP-RMCF0402-IPC_C"
		(layer "F.Cu")
		(at 142.901105 90.4036 -90)
		(property "Reference" "R9"
			(at 1.349995 -0.000025 270)
			(unlocked yes)
			(layer "F.SilkS")
			(effects
				(font
					(face "Arial")
					(size 0.40005 0.40005)
					(thickness 0.178)
				)
			)
		)
		(property "Value" "100k"
			(at 6.538115 1.947571 270)
			(unlocked yes)
			(layer "F.SilkS")
			(hide yes)
			(effects
				(font
					(face "Arial")
					(size 0.96012 0.96012)
					(thickness 0.254)
				)
			)
		)
		(sheetname "02-Antenna_Supervisor")
		(sheetfile "02-Antenna_Supervisor.kicad_sch")
		(duplicate_pad_numbers_are_jumpers no)
		(fp_line
			(start -0.75607 0.375)
			(end -0.75607 -0.375)
			(stroke
				(width 0.2)
				(type solid)
			)
			(layer "F.CrtYd")
		)
		(fp_line
			(start 0.75607 0.375)
			(end -0.75607 0.375)
			(stroke
				(width 0.2)
				(type solid)
			)
			(layer "F.CrtYd")
		)
		(fp_line
			(start 0.75607 0.375)
			(end 0.75607 -0.375)
			(stroke
				(width 0.2)
				(type solid)
			)
			(layer "F.CrtYd")
		)
		(fp_line
			(start 0.75607 -0.375)
			(end -0.75607 -0.375)
			(stroke
				(width 0.2)
				(type solid)
			)
			(layer "F.CrtYd")
		)
		(fp_line
			(start 0 0.5)
			(end 0 -0.5)
			(stroke
				(width 0.1)
				(type solid)
			)
			(layer "F.Fab")
		)
		(fp_line
			(start -0.75607 0.375)
			(end -0.75607 -0.375)
			(stroke
				(width 0.2)
				(type solid)
			)
			(layer "F.Fab")
		)
		(fp_line
			(start 0.75607 0.375)
			(end -0.75607 0.375)
			(stroke
				(width 0.2)
				(type solid)
			)
			(layer "F.Fab")
		)
		(fp_line
			(start 0.75607 0.375)
			(end 0.75607 -0.375)
			(stroke
				(width 0.2)
				(type solid)
			)
			(layer "F.Fab")
		)
		(fp_line
			(start 0.5 0)
			(end -0.5 0)
			(stroke
				(width 0.1)
				(type solid)
			)
			(layer "F.Fab")
		)
		(fp_line
			(start 0.75607 -0.375)
			(end -0.75607 -0.375)
			(stroke
				(width 0.2)
				(type solid)
			)
			(layer "F.Fab")
		)
		(fp_text user "${REFERENCE}"
			(at -0.00001 0.09602 270)
			(unlocked yes)
			(layer "F.Fab")
			(effects
				(font
					(face "Arial")
					(size 0.63 0.63)
					(thickness 0.1)
				)
				(justify left bottom)
			)
		)
		(pad "1" smd rect
			(at -0.36554 0 270)
			(size 0.58106 0.47247)
			(layers "F.Cu" "F.Mask" "F.Paste")
			(net "NetQ1_1")
			(solder_mask_margin 0)
			(solder_paste_margin 0)
		)
		(pad "2" smd rect
			(at 0.36554 0 270)
			(size 0.58106 0.47247)
			(layers "F.Cu" "F.Mask" "F.Paste")
			(net "+3V3")
			(solder_mask_margin 0)
			(solder_paste_margin 0)
		)
	)
	(footprint "Vault:FP-LQG15HH_02-IPC_B"
		(layer "F.Cu")
		(at 154.188925 89.52566)
		(property "Reference" "L1"
			(at 1.616665 0.098335 0)
			(unlocked yes)
			(layer "F.SilkS")
			(effects
				(font
					(face "Arial")
					(size 0.40005 0.40005)
					(thickness 0.1778)
				)
			)
		)
		(property "Value" "47nH 300mA"
			(at 12.784545 2.012615 0)
			(unlocked yes)
			(layer "F.SilkS")
			(hide yes)
			(effects
				(font
					(face "Arial")
					(size 0.40005 0.40005)
					(thickness 0.1778)
				)
			)
		)
		(sheetname "02-Antenna_Supervisor")
		(sheetfile "02-Antenna_Supervisor.kicad_sch")
		(duplicate_pad_numbers_are_jumpers no)
		(fp_line
			(start -0.88624 -0.43624)
			(end 0.88624 -0.43624)
			(stroke
				(width 0.2)
				(type solid)
			)
			(layer "F.CrtYd")
		)
		(fp_line
			(start -0.88624 0.43623)
			(end -0.88624 -0.43624)
			(stroke
				(width 0.2)
				(type solid)
			)
			(layer "F.CrtYd")
		)
		(fp_line
			(start -0.88624 0.43623)
			(end 0.88624 0.43623)
			(stroke
				(width 0.2)
				(type solid)
			)
			(layer "F.CrtYd")
		)
		(fp_line
			(start 0.88624 0.43623)
			(end 0.88624 -0.43624)
			(stroke
				(width 0.2)
				(type solid)
			)
			(layer "F.CrtYd")
		)
		(fp_line
			(start -0.88624 -0.43624)
			(end 0.88624 -0.43624)
			(stroke
				(width 0.2)
				(type solid)
			)
			(layer "F.Fab")
		)
		(fp_line
			(start -0.88624 0.43623)
			(end -0.88624 -0.43624)
			(stroke
				(width 0.2)
				(type solid)
			)
			(layer "F.Fab")
		)
		(fp_line
			(start -0.88624 0.43623)
			(end 0.88624 0.43623)
			(stroke
				(width 0.2)
				(type solid)
			)
			(layer "F.Fab")
		)
		(fp_line
			(start -0.5 0)
			(end 0.5 0)
			(stroke
				(width 0.1)
				(type solid)
			)
			(layer "F.Fab")
		)
		(fp_line
			(start 0 0.5)
			(end 0 -0.5)
			(stroke
				(width 0.1)
				(type solid)
			)
			(layer "F.Fab")
		)
		(fp_line
			(start 0.88624 0.43623)
			(end 0.88624 -0.43624)
			(stroke
				(width 0.2)
				(type solid)
			)
			(layer "F.Fab")
		)
		(fp_text user "${REFERENCE}"
			(at 0 0.29534 360)
			(unlocked yes)
			(layer "F.Fab")
			(effects
				(font
					(face "Arial")
					(size 0.63 0.63)
					(thickness 0.1)
				)
				(justify left bottom)
			)
		)
		(pad "1" smd rect
			(at -0.42856 0)
			(size 0.61535 0.57247)
			(layers "F.Cu" "F.Mask" "F.Paste")
			(net "NetC12_1")
			(solder_mask_margin 0)
			(solder_paste_margin 0)
		)
		(pad "2" smd rect
			(at 0.42856 0)
			(size 0.61535 0.57247)
			(layers "F.Cu" "F.Mask" "F.Paste")
			(net "RF_ANT")
			(solder_mask_margin 0)
			(solder_paste_margin 0)
		)
	)
	(footprint "Vault:RESC1005X40X25NL05T10"
		(layer "F.Cu")
		(at 147.901105 118.2036 90)
		(property "Reference" "R15"
			(at 1.7 -0.099924 90)
			(unlocked yes)
			(layer "F.SilkS")
			(effects
				(font
					(face "Arial")
					(size 0.48006 0.48006)
					(thickness 0.254)
				)
			)
		)
		(property "Value" "0_5%_0402"
			(at -2.385841 6.512925 0)
			(unlocked yes)
			(layer "F.SilkS")
			(hide yes)
			(effects
				(font
					(face "Arial")
					(size 0.96012 0.96012)
					(thickness 0.254)
				)
			)
		)
		(sheetname "03-M2_GoldFingers")
		(sheetfile "03-M2_GoldFingers.kicad_sch")
		(duplicate_pad_numbers_are_jumpers no)
		(fp_line
			(start 0.9 -0.45)
			(end 0.9 0.45)
			(stroke
				(width 0.05)
				(type solid)
			)
			(layer "F.CrtYd")
		)
		(fp_line
			(start -0.9 -0.45)
			(end 0.9 -0.45)
			(stroke
				(width 0.05)
				(type solid)
			)
			(layer "F.CrtYd")
		)
		(fp_line
			(start -0.9 -0.45)
			(end -0.9 0.45)
			(stroke
				(width 0.05)
				(type solid)
			)
			(layer "F.CrtYd")
		)
		(fp_line
			(start 0 -0.275)
			(end 0 0.275)
			(stroke
				(width 0.1)
				(type solid)
			)
			(layer "F.CrtYd")
		)
		(fp_line
			(start -0.275 0)
			(end 0.275 0)
			(stroke
				(width 0.1)
				(type solid)
			)
			(layer "F.CrtYd")
		)
		(fp_line
			(start -0.9 0.45)
			(end 0.9 0.45)
			(stroke
				(width 0.05)
				(type solid)
			)
			(layer "F.CrtYd")
		)
		(pad "1" smd rect
			(at -0.425 0 180)
			(size 0.55 0.6)
			(layers "F.Cu" "F.Mask" "F.Paste")
			(net "NetJ1_46")
		)
		(pad "2" smd rect
			(at 0.425 0 180)
			(size 0.55 0.6)
			(layers "F.Cu" "F.Mask" "F.Paste")
			(net "TP1")
		)
	)
	(footprint "Vault:ONSC-SOT-23-3-318-08_V"
		(layer "F.Cu")
		(at 145.101105 90.8036)
		(property "Reference" "Q1"
			(at 2.042805 1.400005 270)
			(unlocked yes)
			(layer "F.SilkS")
			(effects
				(font
					(face "Arial")
					(size 0.40005 0.40005)
					(thickness 0.1778)
				)
			)
		)
		(property "Value" "NTR2101PT1G"
			(at 7.629825 3.173111 0)
			(unlocked yes)
			(layer "F.SilkS")
			(hide yes)
			(effects
				(font
					(face "Arial")
					(size 0.96012 0.96012)
					(thickness 0.254)
				)
			)
		)
		(sheetname "02-Antenna_Supervisor")
		(sheetfile "02-Antenna_Supervisor.kicad_sch")
		(duplicate_pad_numbers_are_jumpers no)
		(fp_line
			(start -0.165 -1.46)
			(end 0.65 -1.46)
			(stroke
				(width 0.2)
				(type solid)
			)
			(layer "F.SilkS")
		)
		(fp_line
			(start -0.165 1.46)
			(end 0.65 1.46)
			(stroke
				(width 0.2)
				(type solid)
			)
			(layer "F.SilkS")
		)
		(fp_line
			(start 0.65 -0.8)
			(end 0.65 -1.46)
			(stroke
				(width 0.2)
				(type solid)
			)
			(layer "F.SilkS")
		)
		(fp_line
			(start 0.65 1.46)
			(end 0.65 0.8)
			(stroke
				(width 0.2)
				(type solid)
			)
			(layer "F.SilkS")
		)
		(fp_circle
			(center -2.05607 -1.477)
			(end -2.05607 -1.602)
			(stroke
				(width 0.25)
				(type solid)
			)
			(fill no)
			(layer "F.SilkS")
		)
		(fp_line
			(start -1.55 -1.56)
			(end 1.55 -1.56)
			(stroke
				(width 0.05)
				(type solid)
			)
			(layer "F.CrtYd")
		)
		(fp_line
			(start -1.55 1.56)
			(end -1.55 -1.56)
			(stroke
				(width 0.05)
				(type solid)
			)
			(layer "F.CrtYd")
		)
		(fp_line
			(start -1.55 1.56)
			(end 1.55 1.56)
			(stroke
				(width 0.05)
				(type solid)
			)
			(layer "F.CrtYd")
		)
		(fp_line
			(start -0.5 0)
			(end 0.5 0)
			(stroke
				(width 0.1)
				(type solid)
			)
			(layer "F.CrtYd")
		)
		(fp_line
			(start 0 0.5)
			(end 0 -0.5)
			(stroke
				(width 0.1)
				(type solid)
			)
			(layer "F.CrtYd")
		)
		(fp_line
			(start 1.55 1.56)
			(end 1.55 -1.56)
			(stroke
				(width 0.05)
				(type solid)
			)
			(layer "F.CrtYd")
		)
		(pad "1" smd rect
			(at -1 -0.95 90)
			(size 0.8 0.9)
			(layers "F.Cu" "F.Mask" "F.Paste")
			(net "NetQ1_1")
		)
		(pad "2" smd rect
			(at -1 0.95 90)
			(size 0.8 0.9)
			(layers "F.Cu" "F.Mask" "F.Paste")
			(net "+3V3")
		)
		(pad "3" smd rect
			(at 1 0 90)
			(size 0.8 0.9)
			(layers "F.Cu" "F.Mask" "F.Paste")
			(net "NetQ1_3")
		)
	)
	(footprint "Vault:FP-RMCF0402-MFG"
		(layer "F.Cu")
		(at 138.601105 91.6036 -90)
		(property "Reference" "R18"
			(at 2.700005 2.898979 90)
			(unlocked yes)
			(layer "F.SilkS")
			(effects
				(font
					(face "Arial")
					(size 0.96012 0.96012)
					(thickness 0.254)
				)
			)
		)
		(property "Value" "1k"
			(at -2.286231 0.46957 180)
			(unlocked yes)
			(layer "F.SilkS")
			(hide yes)
			(effects
				(font
					(face "Arial")
					(size 0.96012 0.96012)
					(thickness 0.254)
				)
			)
		)
		(sheetname "02-Antenna_Supervisor")
		(sheetfile "02-Antenna_Supervisor.kicad_sch")
		(duplicate_pad_numbers_are_jumpers no)
		(fp_line
			(start -0.85 0.4)
			(end -0.85 -0.4)
			(stroke
				(width 0.2)
				(type solid)
			)
			(layer "F.CrtYd")
		)
		(fp_line
			(start 0.85 0.4)
			(end -0.85 0.4)
			(stroke
				(width 0.2)
				(type solid)
			)
			(layer "F.CrtYd")
		)
		(fp_line
			(start 0.85 0.4)
			(end 0.85 -0.4)
			(stroke
				(width 0.2)
				(type solid)
			)
			(layer "F.CrtYd")
		)
		(fp_line
			(start 0.85 -0.4)
			(end -0.85 -0.4)
			(stroke
				(width 0.2)
				(type solid)
			)
			(layer "F.CrtYd")
		)
		(fp_line
			(start 0 0.5)
			(end 0 -0.5)
			(stroke
				(width 0.1)
				(type solid)
			)
			(layer "F.Fab")
		)
		(fp_line
			(start -0.85 0.4)
			(end -0.85 -0.4)
			(stroke
				(width 0.2)
				(type solid)
			)
			(layer "F.Fab")
		)
		(fp_line
			(start 0.85 0.4)
			(end -0.85 0.4)
			(stroke
				(width 0.2)
				(type solid)
			)
			(layer "F.Fab")
		)
		(fp_line
			(start 0.85 0.4)
			(end 0.85 -0.4)
			(stroke
				(width 0.2)
				(type solid)
			)
			(layer "F.Fab")
		)
		(fp_line
			(start 0.5 0)
			(end -0.5 0)
			(stroke
				(width 0.1)
				(type solid)
			)
			(layer "F.Fab")
		)
		(fp_line
			(start 0.85 -0.4)
			(end -0.85 -0.4)
			(stroke
				(width 0.2)
				(type solid)
			)
			(layer "F.Fab")
		)
		(fp_text user "${REFERENCE}"
			(at -0.00001 0.09602 270)
			(unlocked yes)
			(layer "F.Fab")
			(effects
				(font
					(face "Arial")
					(size 0.63 0.63)
					(thickness 0.1)
				)
				(justify left bottom)
			)
		)
		(pad "1" smd rect
			(at -0.5 0 270)
			(size 0.5 0.6)
			(layers "F.Cu" "F.Mask" "F.Paste")
			(net "ANT_SHORT_N")
			(solder_mask_margin 0)
			(solder_paste_margin 0)
		)
		(pad "2" smd rect
			(at 0.5 0 270)
			(size 0.5 0.6)
			(layers "F.Cu" "F.Mask" "F.Paste")
			(net "+3V3")
			(solder_mask_margin 0)
			(solder_paste_margin 0)
		)
	)
)
